# T6G (Grand Teton) — schematic netlist excerpt (pin names and nets, part order shuffled) for the footprints in the layout excerpt that follows; sources: Cadence DE-HDL packaged netlist, KiCad conversion of 04192023_DAF0TMB3IC0_F0TG_MB_C_brd_V02_OCP.brd

U257  74LVC2G07DW7  74LVC2G07DW-7 IC  pkg SOT363_0-65_2X1-25XC  page 129
  \1a\  = GPU_FPGA_EROT_RECOV_N
  GND  = GND
  \2a\  = GND
  \2y\  = NC_U257_2Y
  VCC  = P3V3_AUX
  \1y\  = GPU_FPGA_EROT_RECOV_BUF_R_N

C808  Q_CAP_DIFFBUS  DIFF BUS_0.22UF 6.3V 20% X6S  pkg C0201  page 65 : \1\ = P5E_CPU1_P0_TX_C_DN<14> ; \2\ = P5E_CPU1_P0_TX_DN<14>
R6075  Q_RES  0 5% CHIP  pkg 0402LF  page 85 : A = LED_HDD_ACTIVITY_B_N ; B = LED_HDD_ACTIVITY_B_PLD_N

(kicad_pcb
	(version 20260206)
	(generator "pcbnew")
	(generator_version "10.0")
	(general
		(thickness 1.6)
		(legacy_teardrops no)
	)
	(paper "A4")
	(title_block
		(title "04192023_DAF0TMB3IC0_F0TG_MB_C_brd_V02_OCP.brd")
		(comment 1 "Grand Teton / footprints 2226-2228 of 8354")
	)
	(layers
		(0 "F.Cu" signal "TOP")
		(4 "In1.Cu" signal "GND")
		(6 "In2.Cu" signal "IN1")
		(8 "In3.Cu" signal "GND1")
		(10 "In4.Cu" signal "IN2")
		(12 "In5.Cu" signal "GND2")
		(14 "In6.Cu" signal "IN3")
		(16 "In7.Cu" signal "GND3")
		(18 "In8.Cu" signal "VCC")
		(20 "In9.Cu" signal "VCC1")
		(22 "In10.Cu" signal "GND4")
		(24 "In11.Cu" signal "IN4")
		(26 "In12.Cu" signal "GND5")
		(28 "In13.Cu" signal "IN5")
		(30 "In14.Cu" signal "GND6")
		(32 "In15.Cu" signal "IN6")
		(34 "In16.Cu" signal "GND7")
		(2 "B.Cu" signal "BOTTOM")
		(9 "F.Adhes" user "F.Adhesive")
		(11 "B.Adhes" user "B.Adhesive")
		(13 "F.Paste" user "Package Geometry/Pastemask Top")
		(15 "B.Paste" user "Package Geometry/Pastemask Bottom")
		(5 "F.SilkS" user "Ref Des/Silkscreen Top")
		(7 "B.SilkS" user "Ref Des/Silkscreen Bottom")
		(1 "F.Mask" user "Board Geometry/Soldermask Top")
		(3 "B.Mask" user "Board Geometry/Soldermask Bottom")
		(17 "Dwgs.User" user "User.Drawings")
		(19 "Cmts.User" user "User.Comments")
		(21 "Eco1.User" user "User.Eco1")
		(23 "Eco2.User" user "User.Eco2")
		(25 "Edge.Cuts" user "Board Geometry/Outline")
		(27 "Margin" user)
		(31 "F.CrtYd" user "Package Geometry/Place Bound Top")
		(29 "B.CrtYd" user "Package Geometry/Place Bound Bottom")
		(35 "F.Fab" user "Ref Des/Assembly Top")
		(33 "B.Fab" user "Ref Des/Assembly Bottom")
	)
	(footprint ""
		(layer "F.Cu")
		(at 185.801 -92.674948 90)
		(property "Reference" "R6075"
			(at 0 0 90)
			(layer "F.SilkS")
			(hide yes)
			(effects
				(font
					(size 1.27 1.27)
				)
			)
		)
		(property "Value" ""
			(at 0 0 90)
			(layer "F.Fab")
			(effects
				(font
					(size 1.27 1.27)
				)
			)
		)
		(duplicate_pad_numbers_are_jumpers no)
		(fp_line
			(start 0.7874 -0.4064)
			(end 0.7874 0.4064)
			(stroke
				(width 0.1524)
				(type default)
			)
			(layer "F.SilkS")
		)
		(fp_line
			(start -0.7874 -0.4064)
			(end 0.7874 -0.4064)
			(stroke
				(width 0.1524)
				(type default)
			)
			(layer "F.SilkS")
		)
		(fp_line
			(start 0.7874 0.4064)
			(end -0.7874 0.4064)
			(stroke
				(width 0.1524)
				(type default)
			)
			(layer "F.SilkS")
		)
		(fp_line
			(start -0.7874 0.4064)
			(end -0.7874 -0.4064)
			(stroke
				(width 0.1524)
				(type default)
			)
			(layer "F.SilkS")
		)
		(fp_line
			(start -0.12065 -0.305054)
			(end -0.12065 -0.2794)
			(stroke
				(width 0.1)
				(type default)
			)
			(layer "F.Fab")
		)
		(fp_line
			(start -0.67945 -0.305054)
			(end -0.12065 -0.305054)
			(stroke
				(width 0.1)
				(type default)
			)
			(layer "F.Fab")
		)
		(fp_line
			(start 0.67945 -0.3048)
			(end 0.67945 0.3048)
			(stroke
				(width 0.1)
				(type default)
			)
			(layer "F.Fab")
		)
		(fp_line
			(start 0.12065 -0.3048)
			(end 0.67945 -0.3048)
			(stroke
				(width 0.1)
				(type default)
			)
			(layer "F.Fab")
		)
		(fp_line
			(start 0.12065 -0.2794)
			(end 0.12065 -0.3048)
			(stroke
				(width 0.1)
				(type default)
			)
			(layer "F.Fab")
		)
		(fp_line
			(start -0.12065 -0.2794)
			(end 0.12065 -0.2794)
			(stroke
				(width 0.1)
				(type default)
			)
			(layer "F.Fab")
		)
		(fp_line
			(start 0.120396 0.2794)
			(end -0.12065 0.2794)
			(stroke
				(width 0.1)
				(type default)
			)
			(layer "F.Fab")
		)
		(fp_line
			(start -0.12065 0.2794)
			(end -0.12065 0.3048)
			(stroke
				(width 0.1)
				(type default)
			)
			(layer "F.Fab")
		)
		(fp_line
			(start 0.67945 0.3048)
			(end 0.120396 0.3048)
			(stroke
				(width 0.1)
				(type default)
			)
			(layer "F.Fab")
		)
		(fp_line
			(start 0.120396 0.3048)
			(end 0.120396 0.2794)
			(stroke
				(width 0.1)
				(type default)
			)
			(layer "F.Fab")
		)
		(fp_line
			(start -0.12065 0.3048)
			(end -0.67945 0.3048)
			(stroke
				(width 0.1)
				(type default)
			)
			(layer "F.Fab")
		)
		(fp_line
			(start -0.67945 0.3048)
			(end -0.67945 -0.305054)
			(stroke
				(width 0.1)
				(type default)
			)
			(layer "F.Fab")
		)
		(pad "1" smd circle
			(at -0.40005 0 90)
			(size 0 0)
			(layers "F.Cu" "F.Mask" "F.Paste")
			(net "LED_HDD_ACTIVITY_B_N")
		)
		(pad "2" smd circle
			(at 0.40005 0 90)
			(size 0 0)
			(layers "F.Cu" "F.Mask" "F.Paste")
			(net "LED_HDD_ACTIVITY_B_PLD_N")
		)
	)
	(footprint ""
		(layer "F.Cu")
		(at 69.741034 -376.982228)
		(property "Reference" "C808"
			(at 0 0 0)
			(layer "F.SilkS")
			(hide yes)
			(effects
				(font
					(size 1.27 1.27)
				)
			)
		)
		(property "Value" ""
			(at 0 0 0)
			(layer "F.Fab")
			(effects
				(font
					(size 1.27 1.27)
				)
			)
		)
		(duplicate_pad_numbers_are_jumpers no)
		(fp_line
			(start -0.299974 -0.150114)
			(end 0.299974 -0.150114)
			(stroke
				(width 0.1)
				(type default)
			)
			(layer "F.Fab")
		)
		(fp_line
			(start -0.299974 0.150114)
			(end -0.299974 -0.150114)
			(stroke
				(width 0.1)
				(type default)
			)
			(layer "F.Fab")
		)
		(fp_line
			(start 0.299974 -0.150114)
			(end 0.299974 0.150114)
			(stroke
				(width 0.1)
				(type default)
			)
			(layer "F.Fab")
		)
		(fp_line
			(start 0.299974 0.150114)
			(end -0.299974 0.150114)
			(stroke
				(width 0.1)
				(type default)
			)
			(layer "F.Fab")
		)
		(pad "1" smd rect
			(at -0.2667 0)
			(size 0.3048 0.381)
			(layers "F.Cu" "F.Mask" "F.Paste")
			(net "P5E_CPU1_P0_TX_C_DN<14>")
		)
		(pad "2" smd rect
			(at 0.2667 0)
			(size 0.3048 0.381)
			(layers "F.Cu" "F.Mask" "F.Paste")
			(net "P5E_CPU1_P0_TX_DN<14>")
		)
	)
	(footprint ""
		(layer "F.Cu")
		(at 119.37365 -437.843422 -90)
		(property "Reference" "U257"
			(at 1.368044 1.755648 90)
			(unlocked yes)
			(layer "F.SilkS")
			(effects
				(font
					(size 0.7874 0.5842)
					(thickness 0.1524)
				)
				(justify left)
			)
		)
		(property "Value" ""
			(at 0 0 270)
			(layer "F.Fab")
			(effects
				(font
					(size 1.27 1.27)
				)
			)
		)
		(duplicate_pad_numbers_are_jumpers no)
		(fp_line
			(start -1.38176 1.100074)
			(end 1.38176 1.100074)
			(stroke
				(width 0.1524)
				(type default)
			)
			(layer "F.SilkS")
		)
		(fp_line
			(start 1.38176 1.100074)
			(end 1.38176 -1.100074)
			(stroke
				(width 0.1524)
				(type default)
			)
			(layer "F.SilkS")
		)
		(fp_line
			(start 0 -0.508)
			(end -0.592074 -1.100074)
			(stroke
				(width 0.1524)
				(type default)
			)
			(layer "F.SilkS")
		)
		(fp_line
			(start -1.38176 -1.100074)
			(end -1.38176 1.100074)
			(stroke
				(width 0.1524)
				(type default)
			)
			(layer "F.SilkS")
		)
		(fp_line
			(start -0.592074 -1.100074)
			(end -1.38176 -1.100074)
			(stroke
				(width 0.1524)
				(type default)
			)
			(layer "F.SilkS")
		)
		(fp_line
			(start 0.592074 -1.100074)
			(end 0 -0.508)
			(stroke
				(width 0.1524)
				(type default)
			)
			(layer "F.SilkS")
		)
		(fp_line
			(start 1.38176 -1.100074)
			(end 0.592074 -1.100074)
			(stroke
				(width 0.1524)
				(type default)
			)
			(layer "F.SilkS")
		)
		(fp_poly
			(pts
				(xy -1.998472 -1.387094) (xy -1.687068 -1.698498) (xy -1.531112 -1.231138)
			)
			(stroke
				(width 0)
				(type default)
			)
			(fill yes)
			(layer "F.SilkS")
		)
		(fp_line
			(start -0.674878 1.100074)
			(end 0.674878 1.100074)
			(stroke
				(width 0.1)
				(type default)
			)
			(layer "F.Fab")
		)
		(fp_line
			(start 0.674878 1.100074)
			(end 0.674878 -1.100074)
			(stroke
				(width 0.1)
				(type default)
			)
			(layer "F.Fab")
		)
		(fp_line
			(start -0.674878 -1.100074)
			(end -0.674878 1.100074)
			(stroke
				(width 0.1)
				(type default)
			)
			(layer "F.Fab")
		)
		(fp_line
			(start 0.674878 -1.100074)
			(end -0.674878 -1.100074)
			(stroke
				(width 0.1)
				(type default)
			)
			(layer "F.Fab")
		)
		(fp_poly
			(pts
				(xy -1.9431 -0.870204) (xy -1.50241 -0.649986) (xy -1.9431 -0.429768)
			)
			(stroke
				(width 0)
				(type default)
			)
			(fill yes)
			(layer "F.Fab")
		)
		(pad "1" smd rect
			(at -0.94996 -0.649986 180)
			(size 0.4318 0.6096)
			(layers "F.Cu" "F.Mask" "F.Paste")
			(net "GPU_FPGA_EROT_RECOV_N")
		)
		(pad "2" smd rect
			(at -0.94996 0 180)
			(size 0.4318 0.6096)
			(layers "F.Cu" "F.Mask" "F.Paste")
			(net "GND")
		)
		(pad "3" smd rect
			(at -0.94996 0.649986 180)
			(size 0.4318 0.6096)
			(layers "F.Cu" "F.Mask" "F.Paste")
			(net "GND")
		)
		(pad "4" smd rect
			(at 0.94996 0.649986 180)
			(size 0.4318 0.6096)
			(layers "F.Cu" "F.Mask" "F.Paste")
			(net "NC_U257_2Y")
		)
		(pad "5" smd rect
			(at 0.94996 0 180)
			(size 0.4318 0.6096)
			(layers "F.Cu" "F.Mask" "F.Paste")
			(net "P3V3_AUX")
		)
		(pad "6" smd rect
			(at 0.94996 -0.649986 180)
			(size 0.4318 0.6096)
			(layers "F.Cu" "F.Mask" "F.Paste")
			(net "GPU_FPGA_EROT_RECOV_BUF_R_N")
		)
	)
)
